(kicad_pcb
	(version 20260206)
	(generator "pcbnew")
	(generator_version "10.0")
	(general
		(thickness 1.6)
		(legacy_teardrops no)
	)
	(paper "A4")
	(title_block
		(title "v1-chassis-manager — T6M_CM_d_v01_1031_1645.brd")
		(comment 1 "Open CloudServer (Microsoft) / footprints 2354-2363 of 2512")
	)
	(layers
		(0 "F.Cu" signal "TOP")
		(4 "In1.Cu" signal "GND1")
		(6 "In2.Cu" signal "IN1")
		(8 "In3.Cu" signal "VCC1")
		(10 "In4.Cu" signal "VCC2")
		(12 "In5.Cu" signal "GND2")
		(14 "In6.Cu" signal "IN2")
		(16 "In7.Cu" signal "IN3")
		(18 "In8.Cu" signal "GND3")
		(2 "B.Cu" signal "BOTTOM")
		(9 "F.Adhes" user "F.Adhesive")
		(11 "B.Adhes" user "B.Adhesive")
		(13 "F.Paste" user "Package Geometry/Pastemask Top")
		(15 "B.Paste" user "Package Geometry/Pastemask Bottom")
		(5 "F.SilkS" user "Ref Des/Silkscreen Top")
		(7 "B.SilkS" user "Ref Des/Silkscreen Bottom")
		(1 "F.Mask" user "Board Geometry/Soldermask Top")
		(3 "B.Mask" user "Board Geometry/Soldermask Bottom")
		(17 "Dwgs.User" user "User.Drawings")
		(19 "Cmts.User" user "User.Comments")
		(21 "Eco1.User" user "User.Eco1")
		(23 "Eco2.User" user "User.Eco2")
		(25 "Edge.Cuts" user "Board Geometry/Outline")
		(27 "Margin" user)
		(31 "F.CrtYd" user "Package Geometry/Place Bound Top")
		(29 "B.CrtYd" user "Package Geometry/Place Bound Bottom")
		(35 "F.Fab" user "Ref Des/Assembly Top")
		(33 "B.Fab" user "Ref Des/Assembly Bottom")
	)
	(footprint ""
		(layer "B.Cu")
		(at 48.758602 -153.373582 180)
		(property "Reference" "C412"
			(at 11.821922 5.316728 0)
			(unlocked yes)
			(layer "B.SilkS")
			(effects
				(font
					(size 0.7874 0.5842)
					(thickness 0.1524)
				)
				(justify left mirror)
			)
		)
		(property "Value" ""
			(at 0 0 0)
			(layer "B.Fab")
			(effects
				(font
					(size 1.27 1.27)
				)
				(justify mirror)
			)
		)
		(duplicate_pad_numbers_are_jumpers no)
		(fp_line
			(start 0.7874 0.4064)
			(end 0.7874 -0.4064)
			(stroke
				(width 0.1524)
				(type default)
			)
			(layer "B.SilkS")
		)
		(fp_line
			(start 0.7874 -0.4064)
			(end -0.7874 -0.4064)
			(stroke
				(width 0.1524)
				(type default)
			)
			(layer "B.SilkS")
		)
		(fp_line
			(start 0 0.381)
			(end 0 -0.381)
			(stroke
				(width 0.1524)
				(type default)
			)
			(layer "B.SilkS")
		)
		(fp_line
			(start -0.7874 0.4064)
			(end 0.7874 0.4064)
			(stroke
				(width 0.1524)
				(type default)
			)
			(layer "B.SilkS")
		)
		(fp_line
			(start -0.7874 -0.4064)
			(end -0.7874 0.4064)
			(stroke
				(width 0.1524)
				(type default)
			)
			(layer "B.SilkS")
		)
		(fp_poly
			(pts
				(xy 0.5334 0.254) (xy 0.635 0.254) (xy 0.635 0.2286) (xy 0.635 -0.254) (xy 0.5334 -0.254) (xy 0.5334 -0.2794)
				(xy -0.5334 -0.2794) (xy -0.5334 -0.254) (xy -0.635 -0.254) (xy -0.635 0.254) (xy -0.5334 0.254)
				(xy -0.5334 0.2794) (xy 0.508 0.2794) (xy 0.5334 0.2794)
			)
			(stroke
				(width 0)
				(type default)
			)
			(fill no)
			(layer "B.CrtYd")
		)
		(pad "1" smd rect
			(at -0.40005 0)
			(size 0.4572 0.508)
			(layers "B.Cu" "B.Mask" "B.Paste")
			(net "P1V9_LAN1")
		)
		(pad "2" smd rect
			(at 0.40005 0)
			(size 0.4572 0.508)
			(layers "B.Cu" "B.Mask" "B.Paste")
			(net "GND")
		)
	)
	(footprint ""
		(layer "B.Cu")
		(at 185.293 -188.468 -90)
		(property "Reference" "C596"
			(at -1.6764 0.05207 270)
			(unlocked yes)
			(layer "B.SilkS")
			(effects
				(font
					(size 0.7874 0.5842)
					(thickness 0.1524)
				)
				(justify left mirror)
			)
		)
		(property "Value" ""
			(at 0 0 90)
			(layer "B.Fab")
			(effects
				(font
					(size 1.27 1.27)
				)
				(justify mirror)
			)
		)
		(duplicate_pad_numbers_are_jumpers no)
		(fp_line
			(start -0.7874 0.4064)
			(end 0.7874 0.4064)
			(stroke
				(width 0.1524)
				(type default)
			)
			(layer "B.SilkS")
		)
		(fp_line
			(start 0.7874 0.4064)
			(end 0.7874 -0.4064)
			(stroke
				(width 0.1524)
				(type default)
			)
			(layer "B.SilkS")
		)
		(fp_line
			(start 0 0.381)
			(end 0 -0.381)
			(stroke
				(width 0.1524)
				(type default)
			)
			(layer "B.SilkS")
		)
		(fp_line
			(start -0.7874 -0.4064)
			(end -0.7874 0.4064)
			(stroke
				(width 0.1524)
				(type default)
			)
			(layer "B.SilkS")
		)
		(fp_line
			(start 0.7874 -0.4064)
			(end -0.7874 -0.4064)
			(stroke
				(width 0.1524)
				(type default)
			)
			(layer "B.SilkS")
		)
		(fp_poly
			(pts
				(xy 0.5334 0.254) (xy 0.635 0.254) (xy 0.635 0.2286) (xy 0.635 -0.254) (xy 0.5334 -0.254) (xy 0.5334 -0.2794)
				(xy -0.5334 -0.2794) (xy -0.5334 -0.254) (xy -0.635 -0.254) (xy -0.635 0.254) (xy -0.5334 0.254)
				(xy -0.5334 0.2794) (xy 0.508 0.2794) (xy 0.5334 0.2794)
			)
			(stroke
				(width 0)
				(type default)
			)
			(fill no)
			(layer "B.CrtYd")
		)
		(pad "1" smd rect
			(at -0.40005 0 90)
			(size 0.4572 0.508)
			(layers "B.Cu" "B.Mask" "B.Paste")
			(net "POWER_SW3_PWR_CTR_12V_R")
		)
		(pad "2" smd rect
			(at 0.40005 0 90)
			(size 0.4572 0.508)
			(layers "B.Cu" "B.Mask" "B.Paste")
			(net "GND")
		)
	)
	(footprint ""
		(layer "B.Cu")
		(at 68.81876 -185.205624 90)
		(property "Reference" "C689"
			(at 4.15163 0.125984 270)
			(unlocked yes)
			(layer "B.SilkS")
			(effects
				(font
					(size 0.7874 0.5842)
					(thickness 0.1524)
				)
				(justify left mirror)
			)
		)
		(property "Value" ""
			(at 0 0 90)
			(layer "B.Fab")
			(effects
				(font
					(size 1.27 1.27)
				)
				(justify mirror)
			)
		)
		(duplicate_pad_numbers_are_jumpers no)
		(fp_line
			(start 0.7874 -0.4064)
			(end -0.7874 -0.4064)
			(stroke
				(width 0.1524)
				(type default)
			)
			(layer "B.SilkS")
		)
		(fp_line
			(start -0.7874 -0.4064)
			(end -0.7874 0.4064)
			(stroke
				(width 0.1524)
				(type default)
			)
			(layer "B.SilkS")
		)
		(fp_line
			(start 0 0.381)
			(end 0 -0.381)
			(stroke
				(width 0.1524)
				(type default)
			)
			(layer "B.SilkS")
		)
		(fp_line
			(start 0.7874 0.4064)
			(end 0.7874 -0.4064)
			(stroke
				(width 0.1524)
				(type default)
			)
			(layer "B.SilkS")
		)
		(fp_line
			(start -0.7874 0.4064)
			(end 0.7874 0.4064)
			(stroke
				(width 0.1524)
				(type default)
			)
			(layer "B.SilkS")
		)
		(fp_poly
			(pts
				(xy 0.5334 0.254) (xy 0.635 0.254) (xy 0.635 0.2286) (xy 0.635 -0.254) (xy 0.5334 -0.254) (xy 0.5334 -0.2794)
				(xy -0.5334 -0.2794) (xy -0.5334 -0.254) (xy -0.635 -0.254) (xy -0.635 0.254) (xy -0.5334 0.254)
				(xy -0.5334 0.2794) (xy 0.508 0.2794) (xy 0.5334 0.2794)
			)
			(stroke
				(width 0)
				(type default)
			)
			(fill no)
			(layer "B.CrtYd")
		)
		(pad "1" smd rect
			(at -0.40005 0 270)
			(size 0.4572 0.508)
			(layers "B.Cu" "B.Mask" "B.Paste")
			(net "UART_T3_NODE4_RXD")
		)
		(pad "2" smd rect
			(at 0.40005 0 270)
			(size 0.4572 0.508)
			(layers "B.Cu" "B.Mask" "B.Paste")
			(net "GND")
		)
	)
	(footprint ""
		(layer "B.Cu")
		(at 47.297086 -128.359662 180)
		(property "Reference" "C232"
			(at -3.945636 0.017018 0)
			(unlocked yes)
			(layer "B.SilkS")
			(effects
				(font
					(size 0.7874 0.5842)
					(thickness 0.1524)
				)
				(justify left mirror)
			)
		)
		(property "Value" ""
			(at 0 0 0)
			(layer "B.Fab")
			(effects
				(font
					(size 1.27 1.27)
				)
				(justify mirror)
			)
		)
		(duplicate_pad_numbers_are_jumpers no)
		(fp_line
			(start 0.7874 0.4064)
			(end 0.7874 -0.4064)
			(stroke
				(width 0.1524)
				(type default)
			)
			(layer "B.SilkS")
		)
		(fp_line
			(start 0.7874 -0.4064)
			(end -0.7874 -0.4064)
			(stroke
				(width 0.1524)
				(type default)
			)
			(layer "B.SilkS")
		)
		(fp_line
			(start 0 0.381)
			(end 0 -0.381)
			(stroke
				(width 0.1524)
				(type default)
			)
			(layer "B.SilkS")
		)
		(fp_line
			(start -0.7874 0.4064)
			(end 0.7874 0.4064)
			(stroke
				(width 0.1524)
				(type default)
			)
			(layer "B.SilkS")
		)
		(fp_line
			(start -0.7874 -0.4064)
			(end -0.7874 0.4064)
			(stroke
				(width 0.1524)
				(type default)
			)
			(layer "B.SilkS")
		)
		(fp_poly
			(pts
				(xy 0.5334 0.254) (xy 0.635 0.254) (xy 0.635 0.2286) (xy 0.635 -0.254) (xy 0.5334 -0.254) (xy 0.5334 -0.2794)
				(xy -0.5334 -0.2794) (xy -0.5334 -0.254) (xy -0.635 -0.254) (xy -0.635 0.254) (xy -0.5334 0.254)
				(xy -0.5334 0.2794) (xy 0.508 0.2794) (xy 0.5334 0.2794)
			)
			(stroke
				(width 0)
				(type default)
			)
			(fill no)
			(layer "B.CrtYd")
		)
		(pad "1" smd rect
			(at -0.40005 0)
			(size 0.4572 0.508)
			(layers "B.Cu" "B.Mask" "B.Paste")
			(net "P1V538_BMC_NODE1")
		)
		(pad "2" smd rect
			(at 0.40005 0)
			(size 0.4572 0.508)
			(layers "B.Cu" "B.Mask" "B.Paste")
			(net "GND")
		)
	)
	(footprint ""
		(layer "B.Cu")
		(at 75.98029 -82.35315 -90)
		(property "Reference" "C32"
			(at 32.277304 14.4272 270)
			(unlocked yes)
			(layer "B.SilkS")
			(effects
				(font
					(size 0.7874 0.5842)
					(thickness 0.1524)
				)
				(justify left mirror)
			)
		)
		(property "Value" ""
			(at 0 0 90)
			(layer "B.Fab")
			(effects
				(font
					(size 1.27 1.27)
				)
				(justify mirror)
			)
		)
		(duplicate_pad_numbers_are_jumpers no)
		(fp_line
			(start -0.7874 0.4064)
			(end 0.7874 0.4064)
			(stroke
				(width 0.1524)
				(type default)
			)
			(layer "B.SilkS")
		)
		(fp_line
			(start 0.7874 0.4064)
			(end 0.7874 -0.4064)
			(stroke
				(width 0.1524)
				(type default)
			)
			(layer "B.SilkS")
		)
		(fp_line
			(start 0 0.381)
			(end 0 -0.381)
			(stroke
				(width 0.1524)
				(type default)
			)
			(layer "B.SilkS")
		)
		(fp_line
			(start -0.7874 -0.4064)
			(end -0.7874 0.4064)
			(stroke
				(width 0.1524)
				(type default)
			)
			(layer "B.SilkS")
		)
		(fp_line
			(start 0.7874 -0.4064)
			(end -0.7874 -0.4064)
			(stroke
				(width 0.1524)
				(type default)
			)
			(layer "B.SilkS")
		)
		(fp_poly
			(pts
				(xy 0.5334 0.254) (xy 0.635 0.254) (xy 0.635 0.2286) (xy 0.635 -0.254) (xy 0.5334 -0.254) (xy 0.5334 -0.2794)
				(xy -0.5334 -0.2794) (xy -0.5334 -0.254) (xy -0.635 -0.254) (xy -0.635 0.254) (xy -0.5334 0.254)
				(xy -0.5334 0.2794) (xy 0.508 0.2794) (xy 0.5334 0.2794)
			)
			(stroke
				(width 0)
				(type default)
			)
			(fill no)
			(layer "B.CrtYd")
		)
		(pad "1" smd rect
			(at -0.40005 0 90)
			(size 0.4572 0.508)
			(layers "B.Cu" "B.Mask" "B.Paste")
			(net "N32265582")
		)
		(pad "2" smd rect
			(at 0.40005 0 90)
			(size 0.4572 0.508)
			(layers "B.Cu" "B.Mask" "B.Paste")
			(net "GND")
		)
	)
	(footprint ""
		(layer "B.Cu")
		(at 136.633712 -46.953932 90)
		(property "Reference" "R1133"
			(at 3.160268 11.167618 270)
			(unlocked yes)
			(layer "B.SilkS")
			(effects
				(font
					(size 0.7874 0.5842)
					(thickness 0.1524)
				)
				(justify left mirror)
			)
		)
		(property "Value" ""
			(at 0 0 90)
			(layer "B.Fab")
			(effects
				(font
					(size 1.27 1.27)
				)
				(justify mirror)
			)
		)
		(duplicate_pad_numbers_are_jumpers no)
		(fp_line
			(start 0.7874 -0.4064)
			(end -0.7874 -0.4064)
			(stroke
				(width 0.1524)
				(type default)
			)
			(layer "B.SilkS")
		)
		(fp_line
			(start -0.7874 -0.4064)
			(end -0.7874 0.4064)
			(stroke
				(width 0.1524)
				(type default)
			)
			(layer "B.SilkS")
		)
		(fp_line
			(start 0.7874 0.4064)
			(end 0.7874 -0.4064)
			(stroke
				(width 0.1524)
				(type default)
			)
			(layer "B.SilkS")
		)
		(fp_line
			(start -0.7874 0.4064)
			(end 0.7874 0.4064)
			(stroke
				(width 0.1524)
				(type default)
			)
			(layer "B.SilkS")
		)
		(fp_poly
			(pts
				(xy 0.508 0.2794) (xy 0.508 0.2286) (xy 0.635 0.2286) (xy 0.635 -0.254) (xy 0.5334 -0.254) (xy 0.5334 -0.2794)
				(xy -0.5334 -0.2794) (xy -0.5334 -0.254) (xy -0.635 -0.254) (xy -0.635 0.254) (xy -0.5334 0.254)
				(xy -0.5334 0.2794)
			)
			(stroke
				(width 0)
				(type default)
			)
			(fill no)
			(layer "B.CrtYd")
		)
		(pad "1" smd rect
			(at -0.40005 0 270)
			(size 0.4572 0.508)
			(layers "B.Cu" "B.Mask" "B.Paste")
			(net "GND")
		)
		(pad "2" smd rect
			(at 0.40005 0 270)
			(size 0.4572 0.508)
			(layers "B.Cu" "B.Mask" "B.Paste")
			(net "UART_DTR_P3_R_N")
		)
	)
	(footprint ""
		(layer "B.Cu")
		(at 62.742572 -72.767698 -90)
		(property "Reference" "C122"
			(at 31.735522 14.765782 270)
			(unlocked yes)
			(layer "B.SilkS")
			(effects
				(font
					(size 0.7874 0.5842)
					(thickness 0.1524)
				)
				(justify left mirror)
			)
		)
		(property "Value" ""
			(at 0 0 90)
			(layer "B.Fab")
			(effects
				(font
					(size 1.27 1.27)
				)
				(justify mirror)
			)
		)
		(duplicate_pad_numbers_are_jumpers no)
		(fp_line
			(start -0.7874 0.4064)
			(end 0.7874 0.4064)
			(stroke
				(width 0.1524)
				(type default)
			)
			(layer "B.SilkS")
		)
		(fp_line
			(start 0.7874 0.4064)
			(end 0.7874 -0.4064)
			(stroke
				(width 0.1524)
				(type default)
			)
			(layer "B.SilkS")
		)
		(fp_line
			(start 0 0.381)
			(end 0 -0.381)
			(stroke
				(width 0.1524)
				(type default)
			)
			(layer "B.SilkS")
		)
		(fp_line
			(start -0.7874 -0.4064)
			(end -0.7874 0.4064)
			(stroke
				(width 0.1524)
				(type default)
			)
			(layer "B.SilkS")
		)
		(fp_line
			(start 0.7874 -0.4064)
			(end -0.7874 -0.4064)
			(stroke
				(width 0.1524)
				(type default)
			)
			(layer "B.SilkS")
		)
		(fp_poly
			(pts
				(xy 0.5334 0.254) (xy 0.635 0.254) (xy 0.635 0.2286) (xy 0.635 -0.254) (xy 0.5334 -0.254) (xy 0.5334 -0.2794)
				(xy -0.5334 -0.2794) (xy -0.5334 -0.254) (xy -0.635 -0.254) (xy -0.635 0.254) (xy -0.5334 0.254)
				(xy -0.5334 0.2794) (xy 0.508 0.2794) (xy 0.5334 0.2794)
			)
			(stroke
				(width 0)
				(type default)
			)
			(fill no)
			(layer "B.CrtYd")
		)
		(pad "1" smd rect
			(at -0.40005 0 90)
			(size 0.4572 0.508)
			(layers "B.Cu" "B.Mask" "B.Paste")
			(net "P1V05_NODE1")
		)
		(pad "2" smd rect
			(at 0.40005 0 90)
			(size 0.4572 0.508)
			(layers "B.Cu" "B.Mask" "B.Paste")
			(net "GND")
		)
	)
	(footprint ""
		(layer "B.Cu")
		(at 66.095372 -80.514698 90)
		(property "Reference" "C64"
			(at -32.158686 -14.55039 270)
			(unlocked yes)
			(layer "B.SilkS")
			(effects
				(font
					(size 0.7874 0.5842)
					(thickness 0.1524)
				)
				(justify left mirror)
			)
		)
		(property "Value" ""
			(at 0 0 90)
			(layer "B.Fab")
			(effects
				(font
					(size 1.27 1.27)
				)
				(justify mirror)
			)
		)
		(duplicate_pad_numbers_are_jumpers no)
		(fp_line
			(start 0.7874 -0.4064)
			(end -0.7874 -0.4064)
			(stroke
				(width 0.1524)
				(type default)
			)
			(layer "B.SilkS")
		)
		(fp_line
			(start -0.7874 -0.4064)
			(end -0.7874 0.4064)
			(stroke
				(width 0.1524)
				(type default)
			)
			(layer "B.SilkS")
		)
		(fp_line
			(start 0 0.381)
			(end 0 -0.381)
			(stroke
				(width 0.1524)
				(type default)
			)
			(layer "B.SilkS")
		)
		(fp_line
			(start 0.7874 0.4064)
			(end 0.7874 -0.4064)
			(stroke
				(width 0.1524)
				(type default)
			)
			(layer "B.SilkS")
		)
		(fp_line
			(start -0.7874 0.4064)
			(end 0.7874 0.4064)
			(stroke
				(width 0.1524)
				(type default)
			)
			(layer "B.SilkS")
		)
		(fp_poly
			(pts
				(xy 0.5334 0.254) (xy 0.635 0.254) (xy 0.635 0.2286) (xy 0.635 -0.254) (xy 0.5334 -0.254) (xy 0.5334 -0.2794)
				(xy -0.5334 -0.2794) (xy -0.5334 -0.254) (xy -0.635 -0.254) (xy -0.635 0.254) (xy -0.5334 0.254)
				(xy -0.5334 0.2794) (xy 0.508 0.2794) (xy 0.5334 0.2794)
			)
			(stroke
				(width 0)
				(type default)
			)
			(fill no)
			(layer "B.CrtYd")
		)
		(pad "1" smd rect
			(at -0.40005 0 270)
			(size 0.4572 0.508)
			(layers "B.Cu" "B.Mask" "B.Paste")
			(net "PV_VCCP_NODE1")
		)
		(pad "2" smd rect
			(at 0.40005 0 270)
			(size 0.4572 0.508)
			(layers "B.Cu" "B.Mask" "B.Paste")
			(net "GND")
		)
	)
	(footprint ""
		(layer "B.Cu")
		(at 161.76498 -148.854922 90)
		(property "Reference" "C454"
			(at -8.519922 -0.556006 270)
			(unlocked yes)
			(layer "B.SilkS")
			(effects
				(font
					(size 0.7874 0.5842)
					(thickness 0.1524)
				)
				(justify left mirror)
			)
		)
		(property "Value" ""
			(at 0 0 90)
			(layer "B.Fab")
			(effects
				(font
					(size 1.27 1.27)
				)
				(justify mirror)
			)
		)
		(duplicate_pad_numbers_are_jumpers no)
		(fp_line
			(start 0.7874 -0.4064)
			(end -0.7874 -0.4064)
			(stroke
				(width 0.1524)
				(type default)
			)
			(layer "B.SilkS")
		)
		(fp_line
			(start -0.7874 -0.4064)
			(end -0.7874 0.4064)
			(stroke
				(width 0.1524)
				(type default)
			)
			(layer "B.SilkS")
		)
		(fp_line
			(start 0 0.381)
			(end 0 -0.381)
			(stroke
				(width 0.1524)
				(type default)
			)
			(layer "B.SilkS")
		)
		(fp_line
			(start 0.7874 0.4064)
			(end 0.7874 -0.4064)
			(stroke
				(width 0.1524)
				(type default)
			)
			(layer "B.SilkS")
		)
		(fp_line
			(start -0.7874 0.4064)
			(end 0.7874 0.4064)
			(stroke
				(width 0.1524)
				(type default)
			)
			(layer "B.SilkS")
		)
		(fp_poly
			(pts
				(xy 0.5334 0.254) (xy 0.635 0.254) (xy 0.635 0.2286) (xy 0.635 -0.254) (xy 0.5334 -0.254) (xy 0.5334 -0.2794)
				(xy -0.5334 -0.2794) (xy -0.5334 -0.254) (xy -0.635 -0.254) (xy -0.635 0.254) (xy -0.5334 0.254)
				(xy -0.5334 0.2794) (xy 0.508 0.2794) (xy 0.5334 0.2794)
			)
			(stroke
				(width 0)
				(type default)
			)
			(fill no)
			(layer "B.CrtYd")
		)
		(pad "1" smd rect
			(at -0.40005 0 270)
			(size 0.4572 0.508)
			(layers "B.Cu" "B.Mask" "B.Paste")
			(net "P1V9_LAN2")
		)
		(pad "2" smd rect
			(at 0.40005 0 270)
			(size 0.4572 0.508)
			(layers "B.Cu" "B.Mask" "B.Paste")
			(net "GND")
		)
	)
	(footprint ""
		(layer "B.Cu")
		(at 156.19476 -187.872624 -90)
		(property "Reference" "C595"
			(at -4.565396 3.755898 270)
			(unlocked yes)
			(layer "B.SilkS")
			(effects
				(font
					(size 0.7874 0.5842)
					(thickness 0.1524)
				)
				(justify left mirror)
			)
		)
		(property "Value" ""
			(at 0 0 90)
			(layer "B.Fab")
			(effects
				(font
					(size 1.27 1.27)
				)
				(justify mirror)
			)
		)
		(duplicate_pad_numbers_are_jumpers no)
		(fp_line
			(start -0.7874 0.4064)
			(end 0.7874 0.4064)
			(stroke
				(width 0.1524)
				(type default)
			)
			(layer "B.SilkS")
		)
		(fp_line
			(start 0.7874 0.4064)
			(end 0.7874 -0.4064)
			(stroke
				(width 0.1524)
				(type default)
			)
			(layer "B.SilkS")
		)
		(fp_line
			(start 0 0.381)
			(end 0 -0.381)
			(stroke
				(width 0.1524)
				(type default)
			)
			(layer "B.SilkS")
		)
		(fp_line
			(start -0.7874 -0.4064)
			(end -0.7874 0.4064)
			(stroke
				(width 0.1524)
				(type default)
			)
			(layer "B.SilkS")
		)
		(fp_line
			(start 0.7874 -0.4064)
			(end -0.7874 -0.4064)
			(stroke
				(width 0.1524)
				(type default)
			)
			(layer "B.SilkS")
		)
		(fp_poly
			(pts
				(xy 0.5334 0.254) (xy 0.635 0.254) (xy 0.635 0.2286) (xy 0.635 -0.254) (xy 0.5334 -0.254) (xy 0.5334 -0.2794)
				(xy -0.5334 -0.2794) (xy -0.5334 -0.254) (xy -0.635 -0.254) (xy -0.635 0.254) (xy -0.5334 0.254)
				(xy -0.5334 0.2794) (xy 0.508 0.2794) (xy 0.5334 0.2794)
			)
			(stroke
				(width 0)
				(type default)
			)
			(fill no)
			(layer "B.CrtYd")
		)
		(pad "1" smd rect
			(at -0.40005 0 90)
			(size 0.4572 0.508)
			(layers "B.Cu" "B.Mask" "B.Paste")
			(net "I2C_PSU3_R_SDA")
		)
		(pad "2" smd rect
			(at 0.40005 0 90)
			(size 0.4572 0.508)
			(layers "B.Cu" "B.Mask" "B.Paste")
			(net "GND")
		)
	)
)
